# BASEBOARD_FAB2 (Tioga Pass) — schematic netlist excerpt (pin names and nets, part order shuffled) for the footprints in the layout excerpt that follows; sources: Cadence DE-HDL packaged netlist, KiCad conversion of Wiwynn_Tioga_Pass_MB.brd

C7A25  CAP  0.22UF 16V 10% X7R  pkg 0402  page 219 : A = P5V_STBY ; B = GND
C7E14  CAP  1.0UF 16V 10% X6S  pkg 0402  page 241 : A = VR_P5V_STBY_VIN ; B = GND

(kicad_pcb
	(version 20260206)
	(generator "pcbnew")
	(generator_version "10.0")
	(general
		(thickness 1.6)
		(legacy_teardrops no)
	)
	(paper "A4")
	(title_block
		(title "Wiwynn_Tioga_Pass_MB.brd")
		(comment 1 "Tioga Pass / footprints 1364-1365 of 4770")
	)
	(layers
		(0 "F.Cu" signal "TOP")
		(4 "In1.Cu" signal "L2GND")
		(6 "In2.Cu" signal "L3")
		(8 "In3.Cu" signal "L4GND")
		(10 "In4.Cu" signal "L5")
		(12 "In5.Cu" signal "L6GND")
		(14 "In6.Cu" signal "L7VCC")
		(16 "In7.Cu" signal "L8VCC")
		(18 "In8.Cu" signal "L9GND")
		(20 "In9.Cu" signal "L10")
		(22 "In10.Cu" signal "L11GND")
		(24 "In11.Cu" signal "L12")
		(26 "In12.Cu" signal "L13GND")
		(2 "B.Cu" signal "BOTTOM")
		(9 "F.Adhes" user "F.Adhesive")
		(11 "B.Adhes" user "B.Adhesive")
		(13 "F.Paste" user "Package Geometry/Pastemask Top")
		(15 "B.Paste" user "Package Geometry/Pastemask Bottom")
		(5 "F.SilkS" user "Ref Des/Silkscreen Top")
		(7 "B.SilkS" user "Ref Des/Silkscreen Bottom")
		(1 "F.Mask" user "Board Geometry/Soldermask Top")
		(3 "B.Mask" user "Board Geometry/Soldermask Bottom")
		(17 "Dwgs.User" user "User.Drawings")
		(19 "Cmts.User" user "User.Comments")
		(21 "Eco1.User" user "User.Eco1")
		(23 "Eco2.User" user "User.Eco2")
		(25 "Edge.Cuts" user "Board Geometry/Outline")
		(27 "Margin" user)
		(31 "F.CrtYd" user "Package Geometry/Place Bound Top")
		(29 "B.CrtYd" user "Package Geometry/Place Bound Bottom")
		(35 "F.Fab" user "Ref Des/Assembly Top")
		(33 "B.Fab" user "Ref Des/Assembly Bottom")
	)
	(footprint ""
		(layer "F.Cu")
		(at 348.2086 -149.112224 -90)
		(property "Reference" "C7A25"
			(at 0 0 270)
			(layer "F.SilkS")
			(hide yes)
			(effects
				(font
					(size 1.27 1.27)
				)
			)
		)
		(property "Value" ""
			(at 0 0 270)
			(layer "F.Fab")
			(effects
				(font
					(size 1.27 1.27)
				)
			)
		)
		(duplicate_pad_numbers_are_jumpers no)
		(fp_poly
			(pts
				(xy 0.3048 -0.1016) (xy 0.3048 0.9906) (xy -0.3048 0.9906) (xy -0.3048 -0.1016)
			)
			(stroke
				(width 0)
				(type default)
			)
			(fill no)
			(layer "F.CrtYd")
		)
		(fp_line
			(start -0.3048 0.9906)
			(end 0.3048 0.9906)
			(stroke
				(width 0.1)
				(type default)
			)
			(layer "F.Fab")
		)
		(fp_line
			(start 0.3048 0.9906)
			(end 0.3048 -0.1016)
			(stroke
				(width 0.1)
				(type default)
			)
			(layer "F.Fab")
		)
		(fp_line
			(start -0.3048 -0.1016)
			(end -0.3048 0.9906)
			(stroke
				(width 0.1)
				(type default)
			)
			(layer "F.Fab")
		)
		(fp_line
			(start 0.3048 -0.1016)
			(end -0.3048 -0.1016)
			(stroke
				(width 0.1)
				(type default)
			)
			(layer "F.Fab")
		)
		(pad "1" smd rect
			(at 0 0 270)
			(size 0.508 0.508)
			(layers "F.Cu" "F.Mask" "F.Paste")
			(net "P5V_STBY")
		)
		(pad "2" smd rect
			(at 0 0.889 270)
			(size 0.508 0.508)
			(layers "F.Cu" "F.Mask" "F.Paste")
			(net "GND")
		)
		(zone
			(layer "F.Cu")
			(hatch none 0.5)
			(connect_pads
				(clearance 0)
			)
			(min_thickness 0.25)
			(keepout
				(tracks not_allowed)
				(vias allowed)
				(pads allowed)
				(copperpour not_allowed)
				(footprints allowed)
			)
			(placement
				(enabled no)
				(sheetname "")
			)
			(fill
				(thermal_gap 0.5)
				(thermal_bridge_width 0.5)
				(island_removal_mode 0)
			)
			(polygon
				(pts
					(xy 347.5736 -149.366224) (xy 347.5736 -148.858224) (xy 347.9546 -148.858224) (xy 347.9546 -149.366224)
				)
			)
		)
		(zone
			(layer "F.Cu")
			(hatch none 0.5)
			(connect_pads
				(clearance 0)
			)
			(min_thickness 0.25)
			(keepout
				(tracks allowed)
				(vias not_allowed)
				(pads allowed)
				(copperpour not_allowed)
				(footprints allowed)
			)
			(placement
				(enabled no)
				(sheetname "")
			)
			(fill
				(thermal_gap 0.5)
				(thermal_bridge_width 0.5)
				(island_removal_mode 0)
			)
			(polygon
				(pts
					(xy 347.9546 -149.366224) (xy 347.9546 -148.858224) (xy 347.5736 -148.858224) (xy 347.5736 -149.366224)
				)
			)
		)
	)
	(footprint ""
		(layer "F.Cu")
		(at 389.6106 -64.5795)
		(property "Reference" "C7E14"
			(at 0 0 0)
			(layer "F.SilkS")
			(hide yes)
			(effects
				(font
					(size 1.27 1.27)
				)
			)
		)
		(property "Value" ""
			(at 0 0 0)
			(layer "F.Fab")
			(effects
				(font
					(size 1.27 1.27)
				)
			)
		)
		(duplicate_pad_numbers_are_jumpers no)
		(fp_poly
			(pts
				(xy 0.3048 -0.1016) (xy 0.3048 0.9906) (xy -0.3048 0.9906) (xy -0.3048 -0.1016)
			)
			(stroke
				(width 0)
				(type default)
			)
			(fill no)
			(layer "F.CrtYd")
		)
		(fp_line
			(start -0.3048 -0.1016)
			(end -0.3048 0.9906)
			(stroke
				(width 0.1)
				(type default)
			)
			(layer "F.Fab")
		)
		(fp_line
			(start -0.3048 0.9906)
			(end 0.3048 0.9906)
			(stroke
				(width 0.1)
				(type default)
			)
			(layer "F.Fab")
		)
		(fp_line
			(start 0.3048 -0.1016)
			(end -0.3048 -0.1016)
			(stroke
				(width 0.1)
				(type default)
			)
			(layer "F.Fab")
		)
		(fp_line
			(start 0.3048 0.9906)
			(end 0.3048 -0.1016)
			(stroke
				(width 0.1)
				(type default)
			)
			(layer "F.Fab")
		)
		(pad "1" smd rect
			(at 0 0)
			(size 0.508 0.508)
			(layers "F.Cu" "F.Mask" "F.Paste")
			(net "VR_P5V_STBY_VIN")
		)
		(pad "2" smd rect
			(at 0 0.889)
			(size 0.508 0.508)
			(layers "F.Cu" "F.Mask" "F.Paste")
			(net "GND")
		)
		(zone
			(layer "F.Cu")
			(hatch none 0.5)
			(connect_pads
				(clearance 0)
			)
			(min_thickness 0.25)
			(keepout
				(tracks allowed)
				(vias not_allowed)
				(pads allowed)
				(copperpour not_allowed)
				(footprints allowed)
			)
			(placement
				(enabled no)
				(sheetname "")
			)
			(fill
				(thermal_gap 0.5)
				(thermal_bridge_width 0.5)
				(island_removal_mode 0)
			)
			(polygon
				(pts
					(xy 389.3566 -64.3255) (xy 389.8646 -64.3255) (xy 389.8646 -63.9445) (xy 389.3566 -63.9445)
				)
			)
		)
		(zone
			(layer "F.Cu")
			(hatch none 0.5)
			(connect_pads
				(clearance 0)
			)
			(min_thickness 0.25)
			(keepout
				(tracks not_allowed)
				(vias allowed)
				(pads allowed)
				(copperpour not_allowed)
				(footprints allowed)
			)
			(placement
				(enabled no)
				(sheetname "")
			)
			(fill
				(thermal_gap 0.5)
				(thermal_bridge_width 0.5)
				(island_removal_mode 0)
			)
			(polygon
				(pts
					(xy 389.3566 -63.9445) (xy 389.8646 -63.9445) (xy 389.8646 -64.3255) (xy 389.3566 -64.3255)
				)
			)
		)
	)
)
